(kicad_pcb
	(version 20211014)
	(generator pcbnew)
	(general
    (thickness 1.6)
  )
	(paper "A4")
	(title_block
    (title "SA800U (Snapdragon 845) Baseboard")
    (date "2023-10-19")
    (rev "1.0.3")
    (company "Antmicro Ltd.")
    (comment 1 "www.antmicro.com")
		(comment 9 "footprint 58 of 589 (U11), pads 101-194 of 348")
	)
	(layers
    (0 "F.Cu" signal)
    (1 "In1.Cu" power)
    (2 "In2.Cu" signal)
    (3 "In3.Cu" signal)
    (4 "In4.Cu" power)
    (31 "B.Cu" signal)
    (32 "B.Adhes" user "B.Adhesive")
    (33 "F.Adhes" user "F.Adhesive")
    (34 "B.Paste" user)
    (35 "F.Paste" user)
    (36 "B.SilkS" user "B.Silkscreen")
    (37 "F.SilkS" user "F.Silkscreen")
    (38 "B.Mask" user)
    (39 "F.Mask" user)
    (40 "Dwgs.User" user "User.Drawings")
    (41 "Cmts.User" user "User.Comments")
    (42 "Eco1.User" user "User.Eco1")
    (43 "Eco2.User" user "User.Eco2")
    (44 "Edge.Cuts" user)
    (45 "Margin" user)
    (46 "B.CrtYd" user "B.Courtyard")
    (47 "F.CrtYd" user "F.Courtyard")
    (48 "B.Fab" user)
    (49 "F.Fab" user)
  )
	(footprint "sa800u-baseboard-hw-footprints:Receptacle_SA800U-WF" locked
    (layer "F.Cu")
    (tedit 6215E1EF)
    (at 112.47 100.96)
    (property "Author" "Antmicro")
    (property "License" "Apache-2.0")
    (property "MPN" "FX10A-168S-SV")
    (property "Manufacturer" "Hirose Electric")
    (property "Sheetfile" "som.kicad_sch")
    (property "Sheetname" "SoM")
    (attr smd)
    (fp_text reference "U11" (at 0.005 -19.31) (layer "F.SilkS")
      (effects (font (size 0.7 0.7) (thickness 0.15)) (justify left bottom))
    )
    (fp_text value "Receptacle_SA800U-WF" (at 0 20.4) (layer "F.Fab")
      (effects (font (size 0.7 0.7) (thickness 0.15)) (justify left bottom))
    )
    (pad "1_93" smd rect locked (at -1.24 -11.426 180) (size 0.33 1.6) (layers "F.Cu" "F.Paste" "F.Mask")
      (net 1 "GND") (pinfunction "GND") (pintype "passive"))
    (pad "1_94" smd rect locked (at -1.24 -17.526 180) (size 0.33 1.6) (layers "F.Cu" "F.Paste" "F.Mask")
      (net 1 "GND") (pinfunction "GND") (pintype "passive"))
    (pad "1_95" smd rect locked (at -1.74 -11.426 180) (size 0.33 1.6) (layers "F.Cu" "F.Paste" "F.Mask")
      (net 596 "/SoM/CAM1_MCLK") (pinfunction "CAM1_MCLK") (pintype "output+no_connect"))
    (pad "1_96" smd rect locked (at -1.74 -17.526 180) (size 0.33 1.6) (layers "F.Cu" "F.Paste" "F.Mask")
      (net 595 "/SoM/CAM1_RST") (pinfunction "CAM1_RST") (pintype "output+no_connect"))
    (pad "1_97" smd rect locked (at -2.239 -11.426 180) (size 0.33 1.6) (layers "F.Cu" "F.Paste" "F.Mask")
      (net 1 "GND") (pinfunction "GND") (pintype "passive"))
    (pad "1_98" smd rect locked (at -2.239 -17.526 180) (size 0.33 1.6) (layers "F.Cu" "F.Paste" "F.Mask")
      (net 594 "/SoM/CAM1_AVDD_EN") (pinfunction "CAM1_AVDD_EN") (pintype "output+no_connect"))
    (pad "1_99" smd rect locked (at -2.741 -11.426 180) (size 0.33 1.6) (layers "F.Cu" "F.Paste" "F.Mask")
      (net 593 "unconnected-(U11-Pad1_99)") (pinfunction "CAM2_MCLK") (pintype "output+no_connect"))
    (pad "1_100" smd rect locked (at -2.741 -17.526 180) (size 0.33 1.6) (layers "F.Cu" "F.Paste" "F.Mask")
      (net 15 "CAM0_RST") (pinfunction "CAM0_RST") (pintype "output"))
    (pad "1_101" smd rect locked (at -3.241 -11.426 180) (size 0.33 1.6) (layers "F.Cu" "F.Paste" "F.Mask")
      (net 1 "GND") (pinfunction "GND") (pintype "power_in"))
    (pad "1_102" smd rect locked (at -3.241 -17.526 180) (size 0.33 1.6) (layers "F.Cu" "F.Paste" "F.Mask")
      (net 592 "/SoM/CAM0_AVDD_EN") (pinfunction "CAM0_AVDD_EN") (pintype "output+no_connect"))
    (pad "1_103" smd rect locked (at -3.741 -11.426 180) (size 0.33 1.6) (layers "F.Cu" "F.Paste" "F.Mask")
      (net 591 "/SoM/CAM3_MCLK") (pinfunction "CAM3_MCLK") (pintype "output+no_connect"))
    (pad "1_104" smd rect locked (at -3.741 -17.526 180) (size 0.33 1.6) (layers "F.Cu" "F.Paste" "F.Mask")
      (net 590 "unconnected-(U11-Pad1_104)") (pinfunction "CAM2_AVDD_EN") (pintype "output+no_connect"))
    (pad "1_105" smd rect locked (at -4.241 -11.426 180) (size 0.33 1.6) (layers "F.Cu" "F.Paste" "F.Mask")
      (net 1 "GND") (pinfunction "GND") (pintype "passive"))
    (pad "1_106" smd rect locked (at -4.241 -17.526 180) (size 0.33 1.6) (layers "F.Cu" "F.Paste" "F.Mask")
      (net 589 "/SoM/LT6911_3V3_EN") (pinfunction "CAM2_PWDN") (pintype "output+no_connect"))
    (pad "1_107" smd rect locked (at -4.741 -11.426 180) (size 0.33 1.6) (layers "F.Cu" "F.Paste" "F.Mask")
      (net 163 "PCIE1_RST_N") (pinfunction "PCIE1_RST_N") (pintype "output"))
    (pad "1_108" smd rect locked (at -4.741 -17.526 180) (size 0.33 1.6) (layers "F.Cu" "F.Paste" "F.Mask")
      (net 588 "/SoM/CAM3_VCC_EN") (pinfunction "CAM3_AVDD_EN") (pintype "output+no_connect"))
    (pad "1_109" smd rect locked (at -5.241 -11.426 180) (size 0.33 1.6) (layers "F.Cu" "F.Paste" "F.Mask")
      (net 162 "PCIE1_CLKREQ_N") (pinfunction "PCIE1_CLKREQ_N") (pintype "input"))
    (pad "1_110" smd rect locked (at -5.241 -17.526 180) (size 0.33 1.6) (layers "F.Cu" "F.Paste" "F.Mask")
      (net 587 "/SoM/RESET_USBHUB") (pinfunction "CAM2_DVDD_EN") (pintype "output+no_connect"))
    (pad "1_111" smd rect locked (at -5.741 -11.426 180) (size 0.33 1.6) (layers "F.Cu" "F.Paste" "F.Mask")
      (net 161 "PCIE1_WAKE_N") (pinfunction "PCIE1_WAKE_N") (pintype "input"))
    (pad "1_112" smd rect locked (at -5.741 -17.526 180) (size 0.33 1.6) (layers "F.Cu" "F.Paste" "F.Mask")
      (net 586 "unconnected-(U11-Pad1_112)") (pinfunction "CAM3_PWDN") (pintype "output+no_connect"))
    (pad "1_113" smd rect locked (at -6.241 -11.426 180) (size 0.33 1.6) (layers "F.Cu" "F.Paste" "F.Mask")
      (net 1 "GND") (pinfunction "GND") (pintype "passive"))
    (pad "1_114" smd rect locked (at -6.241 -17.526 180) (size 0.33 1.6) (layers "F.Cu" "F.Paste" "F.Mask")
      (net 14 "CAM0_PWDN") (pinfunction "CAM0_PWDN") (pintype "output"))
    (pad "1_115" smd rect locked (at -6.741 -11.426 180) (size 0.33 1.6) (layers "F.Cu" "F.Paste" "F.Mask")
      (net 8 "PCIE1_RX_P") (pinfunction "PCIE1_RX_P") (pintype "input"))
    (pad "1_116" smd rect locked (at -6.741 -17.526 180) (size 0.33 1.6) (layers "F.Cu" "F.Paste" "F.Mask")
      (net 585 "unconnected-(U11-Pad1_116)") (pinfunction "CAM1_STROBE") (pintype "output+no_connect"))
    (pad "1_117" smd rect locked (at -7.241 -11.426 180) (size 0.33 1.6) (layers "F.Cu" "F.Paste" "F.Mask")
      (net 9 "PCIE1_RX_N") (pinfunction "PCIE1_RX_M") (pintype "input"))
    (pad "1_118" smd rect locked (at -7.241 -17.526 180) (size 0.33 1.6) (layers "F.Cu" "F.Paste" "F.Mask")
      (net 100 "USB2_FAULT") (pinfunction "CAM2_STROBE") (pintype "input"))
    (pad "1_119" smd rect locked (at -7.741 -11.426 180) (size 0.33 1.6) (layers "F.Cu" "F.Paste" "F.Mask")
      (net 1 "GND") (pinfunction "GND") (pintype "passive"))
    (pad "1_120" smd rect locked (at -7.741 -17.526 180) (size 0.33 1.6) (layers "F.Cu" "F.Paste" "F.Mask")
      (net 16 "CAM1_PWDN") (pinfunction "CAM1_PWDN") (pintype "output"))
    (pad "1_121" smd rect locked (at -8.241 -11.426 180) (size 0.33 1.6) (layers "F.Cu" "F.Paste" "F.Mask")
      (net 47 "PCIE1_REFCLK_P") (pinfunction "PCIE1_REFCLK_P") (pintype "output"))
    (pad "1_122" smd rect locked (at -8.241 -17.526 180) (size 0.33 1.6) (layers "F.Cu" "F.Paste" "F.Mask")
      (net 584 "unconnected-(U11-Pad1_122)") (pinfunction "CAM0_STROBE") (pintype "output+no_connect"))
    (pad "1_123" smd rect locked (at -8.741 -11.426 180) (size 0.33 1.6) (layers "F.Cu" "F.Paste" "F.Mask")
      (net 46 "PCIE1_REFCLK_N") (pinfunction "PCIE1_REFCLK_M") (pintype "output"))
    (pad "1_124" smd rect locked (at -8.741 -17.526 180) (size 0.33 1.6) (layers "F.Cu" "F.Paste" "F.Mask")
      (net 583 "/SoM/PWR_OFF") (pinfunction "CAM2_RST") (pintype "output+no_connect"))
    (pad "1_125" smd rect locked (at -9.241 -11.426 180) (size 0.33 1.6) (layers "F.Cu" "F.Paste" "F.Mask")
      (net 1 "GND") (pinfunction "GND") (pintype "passive"))
    (pad "1_126" smd rect locked (at -9.241 -17.526 180) (size 0.33 1.6) (layers "F.Cu" "F.Paste" "F.Mask")
      (net 582 "/SoM/CAM3_RST") (pinfunction "CAM3_RST") (pintype "output+no_connect"))
    (pad "1_127" smd rect locked (at -9.741 -11.426 180) (size 0.33 1.6) (layers "F.Cu" "F.Paste" "F.Mask")
      (net 48 "PCIE1_TX_N") (pinfunction "PCIE1_TX_M") (pintype "output"))
    (pad "1_128" smd rect locked (at -9.741 -17.526 180) (size 0.33 1.6) (layers "F.Cu" "F.Paste" "F.Mask")
      (net 581 "/SoM/CAM3_TRIGGER_OUT") (pinfunction "CAM3_DVDD_EN") (pintype "output+no_connect"))
    (pad "1_129" smd rect locked (at -10.24 -11.426 180) (size 0.33 1.6) (layers "F.Cu" "F.Paste" "F.Mask")
      (net 49 "PCIE1_TX_P") (pinfunction "PCIE1_TX_P") (pintype "output"))
    (pad "1_130" smd rect locked (at -10.24 -17.526 180) (size 0.33 1.6) (layers "F.Cu" "F.Paste" "F.Mask")
      (net 580 "/SoM/CAM1_DVDD_EN") (pinfunction "CAM1_DVDD_EN") (pintype "output+no_connect"))
    (pad "1_131" smd rect locked (at -10.74 -11.426 180) (size 0.33 1.6) (layers "F.Cu" "F.Paste" "F.Mask")
      (net 1 "GND") (pinfunction "GND") (pintype "passive"))
    (pad "1_132" smd rect locked (at -10.74 -17.526 180) (size 0.33 1.6) (layers "F.Cu" "F.Paste" "F.Mask")
      (net 579 "/SoM/CAM0_DVDD_EN") (pinfunction "CAM0_DVDD_EN") (pintype "output+no_connect"))
    (pad "1_133" smd rect locked (at -11.24 -11.426 180) (size 0.33 1.6) (layers "F.Cu" "F.Paste" "F.Mask")
      (net 578 "/SoM/MAG_INT") (pinfunction "MAG_INT") (pintype "input+no_connect"))
    (pad "1_134" smd rect locked (at -11.24 -17.526 180) (size 0.33 1.6) (layers "F.Cu" "F.Paste" "F.Mask")
      (net 419 "/SoM/AUTO_ON_N") (pinfunction "CBL_PWR_N") (pintype "input"))
    (pad "1_135" smd rect locked (at -11.74 -11.426 180) (size 0.33 1.6) (layers "F.Cu" "F.Paste" "F.Mask")
      (net 577 "/SoM/MAG_DRDY_INT") (pinfunction "MAG_DRDY_INT") (pintype "input+no_connect"))
    (pad "1_136" smd rect locked (at -11.74 -17.526 180) (size 0.33 1.6) (layers "F.Cu" "F.Paste" "F.Mask")
      (net 576 "unconnected-(U11-Pad1_136)") (pinfunction "SSC_SPI1_CS0") (pintype "output+no_connect"))
    (pad "1_137" smd rect locked (at -12.24 -11.426 180) (size 0.33 1.6) (layers "F.Cu" "F.Paste" "F.Mask")
      (net 575 "/SoM/GYRO_INT") (pinfunction "GYRO_INT") (pintype "input+no_connect"))
    (pad "1_138" smd rect locked (at -12.24 -17.526 180) (size 0.33 1.6) (layers "F.Cu" "F.Paste" "F.Mask")
      (net 574 "unconnected-(U11-Pad1_138)") (pinfunction "SSC_SPI1_CS1") (pintype "output+no_connect"))
    (pad "1_139" smd rect locked (at -12.74 -11.426 180) (size 0.33 1.6) (layers "F.Cu" "F.Paste" "F.Mask")
      (net 573 "/SoM/ACCL_INT") (pinfunction "ACCEL_INT") (pintype "input+no_connect"))
    (pad "1_140" smd rect locked (at -12.74 -17.526 180) (size 0.33 1.6) (layers "F.Cu" "F.Paste" "F.Mask")
      (net 572 "unconnected-(U11-Pad1_140)") (pinfunction "SSC_SPI1_CS2") (pintype "output+no_connect"))
    (pad "1_141" smd rect locked (at -13.24 -11.426 180) (size 0.33 1.6) (layers "F.Cu" "F.Paste" "F.Mask")
      (net 571 "unconnected-(U11-Pad1_141)") (pinfunction "SSC_SPI2_CS") (pintype "output+no_connect"))
    (pad "1_142" smd rect locked (at -13.24 -17.526 180) (size 0.33 1.6) (layers "F.Cu" "F.Paste" "F.Mask")
      (net 42 "CCI0_I2C_SCL") (pinfunction "CCI0_I2C_SCL") (pintype "output"))
    (pad "1_143" smd rect locked (at -13.74 -11.426 180) (size 0.33 1.6) (layers "F.Cu" "F.Paste" "F.Mask")
      (net 570 "unconnected-(U11-Pad1_143)") (pinfunction "SSC_SPI2_MOSI") (pintype "output+no_connect"))
    (pad "1_144" smd rect locked (at -13.74 -17.526 180) (size 0.33 1.6) (layers "F.Cu" "F.Paste" "F.Mask")
      (net 43 "CCI0_I2C_SDA") (pinfunction "CCI0_I2C_SDA") (pintype "bidirectional"))
    (pad "1_145" smd rect locked (at -14.24 -11.426 180) (size 0.33 1.6) (layers "F.Cu" "F.Paste" "F.Mask")
      (net 569 "unconnected-(U11-Pad1_145)") (pinfunction "SSC_SPI2_CLK") (pintype "output+no_connect"))
    (pad "1_146" smd rect locked (at -14.24 -17.526 180) (size 0.33 1.6) (layers "F.Cu" "F.Paste" "F.Mask")
      (net 45 "CCI1_I2C_SDA") (pinfunction "CCI1_I2C_SDA") (pintype "bidirectional"))
    (pad "1_147" smd rect locked (at -14.74 -11.426 180) (size 0.33 1.6) (layers "F.Cu" "F.Paste" "F.Mask")
      (net 568 "unconnected-(U11-Pad1_147)") (pinfunction "SSC_SPI2_MISO") (pintype "input+no_connect"))
    (pad "1_148" smd rect locked (at -14.74 -17.526 180) (size 0.33 1.6) (layers "F.Cu" "F.Paste" "F.Mask")
      (net 44 "CCI1_I2C_SCL") (pinfunction "CCI1_I2C_SCL") (pintype "output"))
    (pad "1_149" smd rect locked (at -15.24 -11.426 180) (size 0.33 1.6) (layers "F.Cu" "F.Paste" "F.Mask")
      (net 139 "LVS1A_1V8") (pinfunction "LVS1A_1V8") (pintype "power_in"))
    (pad "1_150" smd rect locked (at -15.24 -17.526 180) (size 0.33 1.6) (layers "F.Cu" "F.Paste" "F.Mask")
      (net 567 "unconnected-(U11-Pad1_150)") (pinfunction "SSC_SPI1_MISO") (pintype "input+no_connect"))
    (pad "1_151" smd rect locked (at -15.74 -11.426 180) (size 0.33 1.6) (layers "F.Cu" "F.Paste" "F.Mask")
      (net 106 "SD_LDO21A") (pinfunction "SD_LDO21A") (pintype "power_in"))
    (pad "1_152" smd rect locked (at -15.74 -17.526 180) (size 0.33 1.6) (layers "F.Cu" "F.Paste" "F.Mask")
      (net 566 "unconnected-(U11-Pad1_152)") (pinfunction "SSC_SPI1_MOSI") (pintype "output+no_connect"))
    (pad "1_153" smd rect locked (at -16.24 -11.426 180) (size 0.33 1.6) (layers "F.Cu" "F.Paste" "F.Mask")
      (net 106 "SD_LDO21A") (pinfunction "SD_LDO21A") (pintype "passive"))
    (pad "1_154" smd rect locked (at -16.24 -17.526 180) (size 0.33 1.6) (layers "F.Cu" "F.Paste" "F.Mask")
      (net 565 "unconnected-(U11-Pad1_154)") (pinfunction "SSC_SPI1_CLK") (pintype "output+no_connect"))
    (pad "1_155" smd rect locked (at -16.74 -11.426 180) (size 0.33 1.6) (layers "F.Cu" "F.Paste" "F.Mask")
      (net 106 "SD_LDO21A") (pinfunction "SD_LDO21A") (pintype "passive"))
    (pad "1_156" smd rect locked (at -16.74 -17.526 180) (size 0.33 1.6) (layers "F.Cu" "F.Paste" "F.Mask")
      (net 1 "GND") (pinfunction "GND") (pintype "passive"))
    (pad "1_157" smd rect locked (at -17.24 -11.426 180) (size 0.33 1.6) (layers "F.Cu" "F.Paste" "F.Mask")
      (net 1 "GND") (pinfunction "GND") (pintype "passive"))
    (pad "1_158" smd rect locked (at -17.24 -17.526 180) (size 0.33 1.6) (layers "F.Cu" "F.Paste" "F.Mask")
      (net 1 "GND") (pinfunction "GND") (pintype "passive"))
    (pad "1_159" smd rect locked (at -17.74 -11.426 180) (size 0.33 1.6) (layers "F.Cu" "F.Paste" "F.Mask")
      (net 424 "/SoM/VBAT_SOM") (pinfunction "VBAT") (pintype "power_in"))
    (pad "1_160" smd rect locked (at -17.74 -17.526 180) (size 0.33 1.6) (layers "F.Cu" "F.Paste" "F.Mask")
      (net 424 "/SoM/VBAT_SOM") (pinfunction "VBAT") (pintype "passive"))
    (pad "1_161" smd rect locked (at -18.24 -11.426 180) (size 0.33 1.6) (layers "F.Cu" "F.Paste" "F.Mask")
      (net 424 "/SoM/VBAT_SOM") (pinfunction "VBAT") (pintype "passive"))
    (pad "1_162" smd rect locked (at -18.24 -17.526 180) (size 0.33 1.6) (layers "F.Cu" "F.Paste" "F.Mask")
      (net 424 "/SoM/VBAT_SOM") (pinfunction "VBAT") (pintype "passive"))
    (pad "1_163" smd rect locked (at -18.74 -11.426 180) (size 0.33 1.6) (layers "F.Cu" "F.Paste" "F.Mask")
      (net 424 "/SoM/VBAT_SOM") (pinfunction "VBAT") (pintype "passive"))
    (pad "1_164" smd rect locked (at -18.74 -17.526 180) (size 0.33 1.6) (layers "F.Cu" "F.Paste" "F.Mask")
      (net 424 "/SoM/VBAT_SOM") (pinfunction "VBAT") (pintype "passive"))
    (pad "1_165" smd rect locked (at -19.24 -11.426 180) (size 0.33 1.6) (layers "F.Cu" "F.Paste" "F.Mask")
      (net 424 "/SoM/VBAT_SOM") (pinfunction "VBAT") (pintype "passive"))
    (pad "1_166" smd rect locked (at -19.24 -17.526 180) (size 0.33 1.6) (layers "F.Cu" "F.Paste" "F.Mask")
      (net 424 "/SoM/VBAT_SOM") (pinfunction "VBAT") (pintype "passive"))
    (pad "1_167" smd rect locked (at -19.74 -11.426 180) (size 0.33 1.6) (layers "F.Cu" "F.Paste" "F.Mask")
      (net 424 "/SoM/VBAT_SOM") (pinfunction "VBAT") (pintype "passive"))
    (pad "1_168" smd rect locked (at -19.74 -17.526 180) (size 0.33 1.6) (layers "F.Cu" "F.Paste" "F.Mask")
      (net 424 "/SoM/VBAT_SOM") (pinfunction "VBAT") (pintype "passive"))
    (pad "1_171" smd rect locked (at 24.961 -14.477 270) (size 3.2 1.6) (layers "F.Cu" "F.Paste" "F.Mask")
      (net 564 "unconnected-(U11-Pad1_171)") (pinfunction "NC") (pintype "no_connect"))
    (pad "1_172" smd rect locked (at -22.939 -14.477 270) (size 3.2 1.6) (layers "F.Cu" "F.Paste" "F.Mask")
      (net 563 "unconnected-(U11-Pad1_172)") (pinfunction "NC") (pintype "no_connect"))
    (pad "2_1" smd rect locked (at 19.76 17.573 180) (size 0.33 1.6) (layers "F.Cu" "F.Paste" "F.Mask")
      (net 93 "SBU_SW_OE") (pinfunction "SBU_SW_OE") (pintype "output"))
    (pad "2_2" smd rect locked (at 19.76 11.473 180) (size 0.33 1.6) (layers "F.Cu" "F.Paste" "F.Mask")
      (net 350 "/SoM/USER_LED") (pinfunction "GPIO_25") (pintype "bidirectional"))
    (pad "2_3" smd rect locked (at 19.26 17.573 180) (size 0.33 1.6) (layers "F.Cu" "F.Paste" "F.Mask")
      (net 98 "SBU_SW_SEL") (pinfunction "SBU_SW_SEL") (pintype "output"))
    (pad "2_4" smd rect locked (at 19.26 11.473 180) (size 0.33 1.6) (layers "F.Cu" "F.Paste" "F.Mask")
      (net 40 "I2C4_SDA") (pinfunction "I2C4_SDA") (pintype "bidirectional"))
    (pad "2_5" smd rect locked (at 18.76 17.573 180) (size 0.33 1.6) (layers "F.Cu" "F.Paste" "F.Mask")
      (net 95 "PWRKEY") (pinfunction "PWRKEY") (pintype "input"))
    (pad "2_6" smd rect locked (at 18.76 11.473 180) (size 0.33 1.6) (layers "F.Cu" "F.Paste" "F.Mask")
      (net 41 "I2C4_SCL") (pinfunction "I2C4_SCL") (pintype "output"))
    (pad "2_7" smd rect locked (at 18.26 17.573 180) (size 0.33 1.6) (layers "F.Cu" "F.Paste" "F.Mask")
      (net 97 "VOL_DOWN") (pinfunction "VOL_DOWN") (pintype "input"))
    (pad "2_8" smd rect locked (at 18.26 11.473 180) (size 0.33 1.6) (layers "F.Cu" "F.Paste" "F.Mask")
      (net 562 "/SoM/SSC_I2C1_SDA") (pinfunction "SSC_I2C1_SDA") (pintype "bidirectional+no_connect"))
    (pad "2_9" smd rect locked (at 17.76 17.573 180) (size 0.33 1.6) (layers "F.Cu" "F.Paste" "F.Mask")
      (net 96 "VOL_UP") (pinfunction "VOL_UP_") (pintype "input"))
    (pad "2_10" smd rect locked (at 17.76 11.473 180) (size 0.33 1.6) (layers "F.Cu" "F.Paste" "F.Mask")
      (net 561 "/SoM/SSC_I2C1_SCL") (pinfunction "SSC_I2C1_SCL") (pintype "output+no_connect"))
    (pad "2_11" smd rect locked (at 17.26 17.573 180) (size 0.33 1.6) (layers "F.Cu" "F.Paste" "F.Mask")
      (net 1 "GND") (pinfunction "GND") (pintype "passive"))
    (pad "2_12" smd rect locked (at 17.26 11.473 180) (size 0.33 1.6) (layers "F.Cu" "F.Paste" "F.Mask")
      (net 1 "GND") (pinfunction "GND") (pintype "passive"))
    (pad "2_13" smd rect locked (at 16.76 17.573 180) (size 0.33 1.6) (layers "F.Cu" "F.Paste" "F.Mask")
      (net 51 "DSI1_LN0_N") (pinfunction "DSI1_LN0_N") (pintype "output"))
    (pad "2_14" smd rect locked (at 16.76 11.473 180) (size 0.33 1.6) (layers "F.Cu" "F.Paste" "F.Mask")
      (net 90 "DSI0_LN3_N") (pinfunction "DSI0_LN3_N") (pintype "output"))
    (pad "2_15" smd rect locked (at 16.26 17.573 180) (size 0.33 1.6) (layers "F.Cu" "F.Paste" "F.Mask")
      (net 176 "DSI1_LN0_P") (pinfunction "DSI1_LN0_P") (pintype "output"))
    (pad "2_16" smd rect locked (at 16.26 11.473 180) (size 0.33 1.6) (layers "F.Cu" "F.Paste" "F.Mask")
      (net 89 "DSI0_LN3_P") (pinfunction "DSI0_LN3_P") (pintype "output"))
  )
)
